# BASEBOARD_FAB2 (Tioga Pass) — schematic netlist excerpt (pin names and nets, part order shuffled) for the footprints in the layout excerpt that follows; sources: Cadence DE-HDL packaged netlist, KiCad conversion of Wiwynn_Tioga_Pass_MB.brd

U8E1  TTL08  74LVC08A IC  pkg QFN15  page 170
  A(0)  = IRQ_FORCE_NM_THROTTLE_N
  B(0)  = FM_OC_DETECT_N
  Y(0)  = FM_FAST_PROCHOT_AND_OUT_0_N
  A(0)  = IRQ_UV_DETECT_N
  B(0)  = FM_HSC_TIMER_EXP_N
  Y(0)  = FM_FAST_PROCHOT_AND_OUT_1_N
  Y(0)  = FM_CTNR_PS_ON_R
  A(0)  = FM_PS_EN
  B(0)  = PWRGD_P12V_HSC_DLY
  Y(0)  = FM_FAST_PROCHOT_THROTTLE_IN_N
  A(0)  = FM_FAST_PROCHOT_AND_OUT_0_N
  B(0)  = FM_FAST_PROCHOT_AND_OUT_1_N

R7F33  RES  4.75K 1% CHIP  pkg 0402  page 161 : A = P5V_STBY ; B = FAN_PWM_OUT_SYS1_R

(kicad_pcb
	(version 20260206)
	(generator "pcbnew")
	(generator_version "10.0")
	(general
		(thickness 1.6)
		(legacy_teardrops no)
	)
	(paper "A4")
	(title_block
		(title "Wiwynn_Tioga_Pass_MB.brd")
		(comment 1 "Tioga Pass / footprints 1268-1269 of 4770")
	)
	(layers
		(0 "F.Cu" signal "TOP")
		(4 "In1.Cu" signal "L2GND")
		(6 "In2.Cu" signal "L3")
		(8 "In3.Cu" signal "L4GND")
		(10 "In4.Cu" signal "L5")
		(12 "In5.Cu" signal "L6GND")
		(14 "In6.Cu" signal "L7VCC")
		(16 "In7.Cu" signal "L8VCC")
		(18 "In8.Cu" signal "L9GND")
		(20 "In9.Cu" signal "L10")
		(22 "In10.Cu" signal "L11GND")
		(24 "In11.Cu" signal "L12")
		(26 "In12.Cu" signal "L13GND")
		(2 "B.Cu" signal "BOTTOM")
		(9 "F.Adhes" user "F.Adhesive")
		(11 "B.Adhes" user "B.Adhesive")
		(13 "F.Paste" user "Package Geometry/Pastemask Top")
		(15 "B.Paste" user "Package Geometry/Pastemask Bottom")
		(5 "F.SilkS" user "Ref Des/Silkscreen Top")
		(7 "B.SilkS" user "Ref Des/Silkscreen Bottom")
		(1 "F.Mask" user "Board Geometry/Soldermask Top")
		(3 "B.Mask" user "Board Geometry/Soldermask Bottom")
		(17 "Dwgs.User" user "User.Drawings")
		(19 "Cmts.User" user "User.Comments")
		(21 "Eco1.User" user "User.Eco1")
		(23 "Eco2.User" user "User.Eco2")
		(25 "Edge.Cuts" user "Board Geometry/Outline")
		(27 "Margin" user)
		(31 "F.CrtYd" user "Package Geometry/Place Bound Top")
		(29 "B.CrtYd" user "Package Geometry/Place Bound Bottom")
		(35 "F.Fab" user "Ref Des/Assembly Top")
		(33 "B.Fab" user "Ref Des/Assembly Bottom")
	)
	(footprint ""
		(layer "F.Cu")
		(at 414.655762 -87.159084 -90)
		(property "Reference" "U8E1"
			(at -3.99669 -0.20828 0)
			(unlocked yes)
			(layer "F.SilkS")
			(effects
				(font
					(size 0.7874 0.5842)
					(thickness 0.1524)
				)
				(justify left)
			)
		)
		(property "Value" ""
			(at 0 0 270)
			(layer "F.Fab")
			(effects
				(font
					(size 1.27 1.27)
				)
			)
		)
		(duplicate_pad_numbers_are_jumpers no)
		(fp_line
			(start -1.82499 1.82499)
			(end -1.82499 1.660144)
			(stroke
				(width 0.1524)
				(type default)
			)
			(layer "F.SilkS")
		)
		(fp_line
			(start -1.411732 1.82499)
			(end -1.82499 1.82499)
			(stroke
				(width 0.1524)
				(type default)
			)
			(layer "F.SilkS")
		)
		(fp_line
			(start 0.088392 1.82499)
			(end -0.089408 1.82499)
			(stroke
				(width 0.1524)
				(type default)
			)
			(layer "F.SilkS")
		)
		(fp_line
			(start 1.82499 1.82499)
			(end 1.410208 1.82499)
			(stroke
				(width 0.1524)
				(type default)
			)
			(layer "F.SilkS")
		)
		(fp_line
			(start 1.82499 1.660144)
			(end 1.82499 1.82499)
			(stroke
				(width 0.1524)
				(type default)
			)
			(layer "F.SilkS")
		)
		(fp_line
			(start -1.82499 -1.660906)
			(end -1.82499 -1.82499)
			(stroke
				(width 0.1524)
				(type default)
			)
			(layer "F.SilkS")
		)
		(fp_line
			(start -1.82499 -1.82499)
			(end -1.411732 -1.82499)
			(stroke
				(width 0.1524)
				(type default)
			)
			(layer "F.SilkS")
		)
		(fp_line
			(start -0.089408 -1.82499)
			(end 0.088392 -1.82499)
			(stroke
				(width 0.1524)
				(type default)
			)
			(layer "F.SilkS")
		)
		(fp_line
			(start 1.410208 -1.82499)
			(end 1.82499 -1.82499)
			(stroke
				(width 0.1524)
				(type default)
			)
			(layer "F.SilkS")
		)
		(fp_line
			(start 1.82499 -1.82499)
			(end 1.82499 -1.660906)
			(stroke
				(width 0.1524)
				(type default)
			)
			(layer "F.SilkS")
		)
		(fp_circle
			(center -1.17856 -2.466086)
			(end -1.17856 -2.593086)
			(stroke
				(width 0.254)
				(type default)
			)
			(fill no)
			(layer "F.SilkS")
		)
		(fp_poly
			(pts
				(xy -1.0287 1.0287) (xy -1.0287 -1.0287) (xy 1.0287 -1.0287) (xy 1.0287 1.0287)
			)
			(stroke
				(width 0)
				(type default)
			)
			(fill yes)
			(layer "F.Paste")
		)
		(fp_rect
			(start -1.82499 1.82499)
			(end 1.82499 -1.82499)
			(stroke
				(width 0)
				(type default)
			)
			(fill no)
			(layer "F.CrtYd")
		)
		(fp_line
			(start -1.82499 1.82499)
			(end -1.82499 -1.82499)
			(stroke
				(width 0.1)
				(type default)
			)
			(layer "F.Fab")
		)
		(fp_line
			(start 1.82499 1.82499)
			(end -1.82499 1.82499)
			(stroke
				(width 0.1)
				(type default)
			)
			(layer "F.Fab")
		)
		(fp_line
			(start -1.82499 -1.82499)
			(end 1.82499 -1.82499)
			(stroke
				(width 0.1)
				(type default)
			)
			(layer "F.Fab")
		)
		(fp_line
			(start 1.82499 -1.82499)
			(end 1.82499 1.82499)
			(stroke
				(width 0.1)
				(type default)
			)
			(layer "F.Fab")
		)
		(fp_circle
			(center -1.17856 -2.466086)
			(end -1.17856 -2.593086)
			(stroke
				(width 0.254)
				(type default)
			)
			(fill no)
			(layer "F.Fab")
		)
		(pad "1" smd rect
			(at -0.750062 -1.664208 270)
			(size 0.3048 0.762)
			(layers "F.Cu" "F.Mask" "F.Paste")
			(net "IRQ_FORCE_NM_THROTTLE_N")
		)
		(pad "2" smd rect
			(at -1.664208 -0.999998 270)
			(size 0.762 0.3048)
			(layers "F.Cu" "F.Mask" "F.Paste")
			(net "FM_OC_DETECT_N")
		)
		(pad "3" smd rect
			(at -1.664208 -0.500126 270)
			(size 0.762 0.3048)
			(layers "F.Cu" "F.Mask" "F.Paste")
			(net "FM_FAST_PROCHOT_AND_OUT_0_N")
		)
		(pad "4" smd rect
			(at -1.664208 0 270)
			(size 0.762 0.3048)
			(layers "F.Cu" "F.Mask" "F.Paste")
			(net "IRQ_UV_DETECT_N")
		)
		(pad "5" smd rect
			(at -1.664208 0.500126 270)
			(size 0.762 0.3048)
			(layers "F.Cu" "F.Mask" "F.Paste")
			(net "FM_HSC_TIMER_EXP_N")
		)
		(pad "6" smd rect
			(at -1.664208 0.999998 270)
			(size 0.762 0.3048)
			(layers "F.Cu" "F.Mask" "F.Paste")
			(net "FM_FAST_PROCHOT_AND_OUT_1_N")
		)
		(pad "7" smd rect
			(at -0.750062 1.664208 270)
			(size 0.3048 0.762)
			(layers "F.Cu" "F.Mask" "F.Paste")
			(net "GND")
		)
		(pad "8" smd rect
			(at 0.750062 1.664208 270)
			(size 0.3048 0.762)
			(layers "F.Cu" "F.Mask" "F.Paste")
			(net "FM_CTNR_PS_ON_R")
		)
		(pad "9" smd rect
			(at 1.664208 0.999998 270)
			(size 0.762 0.3048)
			(layers "F.Cu" "F.Mask" "F.Paste")
			(net "FM_PS_EN")
		)
		(pad "10" smd rect
			(at 1.664208 0.500126 270)
			(size 0.762 0.3048)
			(layers "F.Cu" "F.Mask" "F.Paste")
			(net "PWRGD_P12V_HSC_DLY")
		)
		(pad "11" smd rect
			(at 1.664208 0 270)
			(size 0.762 0.3048)
			(layers "F.Cu" "F.Mask" "F.Paste")
			(net "FM_FAST_PROCHOT_THROTTLE_IN_N")
		)
		(pad "12" smd rect
			(at 1.664208 -0.500126 270)
			(size 0.762 0.3048)
			(layers "F.Cu" "F.Mask" "F.Paste")
			(net "FM_FAST_PROCHOT_AND_OUT_0_N")
		)
		(pad "13" smd rect
			(at 1.664208 -0.999998 270)
			(size 0.762 0.3048)
			(layers "F.Cu" "F.Mask" "F.Paste")
			(net "FM_FAST_PROCHOT_AND_OUT_1_N")
		)
		(pad "14" smd rect
			(at 0.750062 -1.664208 270)
			(size 0.3048 0.762)
			(layers "F.Cu" "F.Mask" "F.Paste")
			(net "P3V3_STBY")
		)
		(pad "15" smd rect
			(at 0 0 270)
			(size 2.0574 2.0574)
			(layers "F.Cu" "F.Mask" "F.Paste")
			(net "GND")
		)
	)
	(footprint ""
		(layer "F.Cu")
		(at 333.726536 -20.801584 90)
		(property "Reference" "R7F33"
			(at 0 0 90)
			(layer "F.SilkS")
			(hide yes)
			(effects
				(font
					(size 1.27 1.27)
				)
			)
		)
		(property "Value" ""
			(at 0 0 90)
			(layer "F.Fab")
			(effects
				(font
					(size 1.27 1.27)
				)
			)
		)
		(duplicate_pad_numbers_are_jumpers no)
		(fp_rect
			(start 0.2794 0.9906)
			(end -0.2794 -0.1016)
			(stroke
				(width 0)
				(type default)
			)
			(fill no)
			(layer "F.CrtYd")
		)
		(fp_line
			(start 0.2794 -0.1016)
			(end -0.2794 -0.1016)
			(stroke
				(width 0.1)
				(type default)
			)
			(layer "F.Fab")
		)
		(fp_line
			(start -0.2794 -0.1016)
			(end -0.2794 0.9906)
			(stroke
				(width 0.1)
				(type default)
			)
			(layer "F.Fab")
		)
		(fp_line
			(start 0.2794 0.9906)
			(end 0.2794 -0.1016)
			(stroke
				(width 0.1)
				(type default)
			)
			(layer "F.Fab")
		)
		(fp_line
			(start -0.2794 0.9906)
			(end 0.2794 0.9906)
			(stroke
				(width 0.1)
				(type default)
			)
			(layer "F.Fab")
		)
		(pad "1" smd rect
			(at 0 0 90)
			(size 0.508 0.508)
			(layers "F.Cu" "F.Mask" "F.Paste")
			(net "P5V_STBY")
		)
		(pad "2" smd rect
			(at 0 0.889 90)
			(size 0.508 0.508)
			(layers "F.Cu" "F.Mask" "F.Paste")
			(net "FAN_PWM_OUT_SYS1_R")
		)
		(zone
			(layer "F.Cu")
			(hatch none 0.5)
			(connect_pads
				(clearance 0)
			)
			(min_thickness 0.25)
			(keepout
				(tracks allowed)
				(vias not_allowed)
				(pads allowed)
				(copperpour not_allowed)
				(footprints allowed)
			)
			(placement
				(enabled no)
				(sheetname "")
			)
			(fill
				(thermal_gap 0.5)
				(thermal_bridge_width 0.5)
				(island_removal_mode 0)
			)
			(polygon
				(pts
					(xy 334.361536 -21.055584) (xy 333.980536 -21.055584) (xy 333.980536 -20.547584) (xy 334.361536 -20.547584)
				)
			)
		)
		(zone
			(layer "F.Cu")
			(hatch none 0.5)
			(connect_pads
				(clearance 0)
			)
			(min_thickness 0.25)
			(keepout
				(tracks not_allowed)
				(vias allowed)
				(pads allowed)
				(copperpour not_allowed)
				(footprints allowed)
			)
			(placement
				(enabled no)
				(sheetname "")
			)
			(fill
				(thermal_gap 0.5)
				(thermal_bridge_width 0.5)
				(island_removal_mode 0)
			)
			(polygon
				(pts
					(xy 334.361536 -21.055584) (xy 333.980536 -21.055584) (xy 333.980536 -20.547584) (xy 334.361536 -20.547584)
				)
			)
		)
	)
)
